# S9S_MB_2U (Grand Teton) — schematic netlist excerpt (pin names and nets, part order shuffled) for the footprints in the layout excerpt that follows; sources: Cadence DE-HDL packaged netlist, KiCad conversion of 03242023_DA0F0TMBIJ0_F0T_Motherboard_J_brd_V01_OCP.brd

C534  Q_CAP  22UF 4V 20% X6S  pkg C0402  page 75 : A = PVCCINFAON_CPU0 ; B = GND
PR4540  Q_RES  20K 1% CHIP  pkg 0402LF  page 242 : A = P12V_SCM_ISET ; B = P12V_SCM_ISET_R

(kicad_pcb
	(version 20260206)
	(generator "pcbnew")
	(generator_version "10.0")
	(general
		(thickness 1.6)
		(legacy_teardrops no)
	)
	(paper "A4")
	(title_block
		(title "03242023_DA0F0TMBIJ0_F0T_Motherboard_J_brd_V01_OCP.brd")
		(comment 1 "Grand Teton / footprints 4459-4460 of 6105")
	)
	(layers
		(0 "F.Cu" signal "TOP")
		(4 "In1.Cu" signal "GND")
		(6 "In2.Cu" signal "IN1")
		(8 "In3.Cu" signal "GND1")
		(10 "In4.Cu" signal "IN2")
		(12 "In5.Cu" signal "GND2")
		(14 "In6.Cu" signal "IN3")
		(16 "In7.Cu" signal "GND3")
		(18 "In8.Cu" signal "VCC")
		(20 "In9.Cu" signal "VCC1")
		(22 "In10.Cu" signal "GND4")
		(24 "In11.Cu" signal "IN4")
		(26 "In12.Cu" signal "GND5")
		(28 "In13.Cu" signal "IN5")
		(30 "In14.Cu" signal "GND6")
		(32 "In15.Cu" signal "IN6")
		(34 "In16.Cu" signal "GND7")
		(2 "B.Cu" signal "BOTTOM")
		(9 "F.Adhes" user "F.Adhesive")
		(11 "B.Adhes" user "B.Adhesive")
		(13 "F.Paste" user "Package Geometry/Pastemask Top")
		(15 "B.Paste" user "Package Geometry/Pastemask Bottom")
		(5 "F.SilkS" user "Ref Des/Silkscreen Top")
		(7 "B.SilkS" user "Ref Des/Silkscreen Bottom")
		(1 "F.Mask" user "Board Geometry/Soldermask Top")
		(3 "B.Mask" user "Board Geometry/Soldermask Bottom")
		(17 "Dwgs.User" user "User.Drawings")
		(19 "Cmts.User" user "User.Comments")
		(21 "Eco1.User" user "User.Eco1")
		(23 "Eco2.User" user "User.Eco2")
		(25 "Edge.Cuts" user "Board Geometry/Outline")
		(27 "Margin" user)
		(31 "F.CrtYd" user "Package Geometry/Place Bound Top")
		(29 "B.CrtYd" user "Package Geometry/Place Bound Bottom")
		(35 "F.Fab" user "Ref Des/Assembly Top")
		(33 "B.Fab" user "Ref Des/Assembly Bottom")
	)
	(footprint ""
		(layer "B.Cu")
		(at 176.97704 -32.951928 -90)
		(property "Reference" "PR4540"
			(at 0 0 90)
			(layer "B.SilkS")
			(hide yes)
			(effects
				(font
					(size 1.27 1.27)
				)
				(justify mirror)
			)
		)
		(property "Value" ""
			(at 0 0 90)
			(layer "B.Fab")
			(effects
				(font
					(size 1.27 1.27)
				)
				(justify mirror)
			)
		)
		(duplicate_pad_numbers_are_jumpers no)
		(fp_line
			(start -0.7874 0.4064)
			(end 0.7874 0.4064)
			(stroke
				(width 0.1524)
				(type default)
			)
			(layer "B.SilkS")
		)
		(fp_line
			(start 0.7874 0.4064)
			(end 0.7874 -0.4064)
			(stroke
				(width 0.1524)
				(type default)
			)
			(layer "B.SilkS")
		)
		(fp_line
			(start -0.7874 -0.4064)
			(end -0.7874 0.4064)
			(stroke
				(width 0.1524)
				(type default)
			)
			(layer "B.SilkS")
		)
		(fp_line
			(start 0.7874 -0.4064)
			(end -0.7874 -0.4064)
			(stroke
				(width 0.1524)
				(type default)
			)
			(layer "B.SilkS")
		)
		(fp_line
			(start -0.67945 0.3048)
			(end -0.120396 0.3048)
			(stroke
				(width 0.1)
				(type default)
			)
			(layer "B.Fab")
		)
		(fp_line
			(start -0.120396 0.3048)
			(end -0.120396 0.2794)
			(stroke
				(width 0.1)
				(type default)
			)
			(layer "B.Fab")
		)
		(fp_line
			(start 0.12065 0.3048)
			(end 0.67945 0.3048)
			(stroke
				(width 0.1)
				(type default)
			)
			(layer "B.Fab")
		)
		(fp_line
			(start 0.67945 0.3048)
			(end 0.67945 -0.305054)
			(stroke
				(width 0.1)
				(type default)
			)
			(layer "B.Fab")
		)
		(fp_line
			(start -0.120396 0.2794)
			(end 0.12065 0.2794)
			(stroke
				(width 0.1)
				(type default)
			)
			(layer "B.Fab")
		)
		(fp_line
			(start 0.12065 0.2794)
			(end 0.12065 0.3048)
			(stroke
				(width 0.1)
				(type default)
			)
			(layer "B.Fab")
		)
		(fp_line
			(start -0.12065 -0.2794)
			(end -0.12065 -0.3048)
			(stroke
				(width 0.1)
				(type default)
			)
			(layer "B.Fab")
		)
		(fp_line
			(start 0.12065 -0.2794)
			(end -0.12065 -0.2794)
			(stroke
				(width 0.1)
				(type default)
			)
			(layer "B.Fab")
		)
		(fp_line
			(start -0.67945 -0.3048)
			(end -0.67945 0.3048)
			(stroke
				(width 0.1)
				(type default)
			)
			(layer "B.Fab")
		)
		(fp_line
			(start -0.12065 -0.3048)
			(end -0.67945 -0.3048)
			(stroke
				(width 0.1)
				(type default)
			)
			(layer "B.Fab")
		)
		(fp_line
			(start 0.12065 -0.305054)
			(end 0.12065 -0.2794)
			(stroke
				(width 0.1)
				(type default)
			)
			(layer "B.Fab")
		)
		(fp_line
			(start 0.67945 -0.305054)
			(end 0.12065 -0.305054)
			(stroke
				(width 0.1)
				(type default)
			)
			(layer "B.Fab")
		)
		(pad "1" smd circle
			(at 0.40005 0 90)
			(size 0 0)
			(layers "B.Cu" "B.Mask" "B.Paste")
			(net "P12V_SCM_ISET")
		)
		(pad "2" smd circle
			(at -0.40005 0 90)
			(size 0 0)
			(layers "B.Cu" "B.Mask" "B.Paste")
			(net "P12V_SCM_ISET_R")
		)
	)
	(footprint ""
		(layer "B.Cu")
		(at 368.158522 -261.953502 -90)
		(property "Reference" "C534"
			(at 0 0 90)
			(layer "B.SilkS")
			(hide yes)
			(effects
				(font
					(size 1.27 1.27)
				)
				(justify mirror)
			)
		)
		(property "Value" ""
			(at 0 0 90)
			(layer "B.Fab")
			(effects
				(font
					(size 1.27 1.27)
				)
				(justify mirror)
			)
		)
		(duplicate_pad_numbers_are_jumpers no)
		(fp_line
			(start -0.7874 0.4064)
			(end 0.7874 0.4064)
			(stroke
				(width 0.1524)
				(type default)
			)
			(layer "B.SilkS")
		)
		(fp_line
			(start 0.7874 0.4064)
			(end 0.7874 -0.4064)
			(stroke
				(width 0.1524)
				(type default)
			)
			(layer "B.SilkS")
		)
		(fp_line
			(start -0.7874 -0.4064)
			(end -0.7874 0.4064)
			(stroke
				(width 0.1524)
				(type default)
			)
			(layer "B.SilkS")
		)
		(fp_line
			(start 0.7874 -0.4064)
			(end -0.7874 -0.4064)
			(stroke
				(width 0.1524)
				(type default)
			)
			(layer "B.SilkS")
		)
		(fp_line
			(start -0.67945 0.3048)
			(end -0.120396 0.3048)
			(stroke
				(width 0.1)
				(type default)
			)
			(layer "B.Fab")
		)
		(fp_line
			(start -0.120396 0.3048)
			(end -0.120396 0.2794)
			(stroke
				(width 0.1)
				(type default)
			)
			(layer "B.Fab")
		)
		(fp_line
			(start 0.12065 0.3048)
			(end 0.67945 0.3048)
			(stroke
				(width 0.1)
				(type default)
			)
			(layer "B.Fab")
		)
		(fp_line
			(start 0.67945 0.3048)
			(end 0.67945 -0.305054)
			(stroke
				(width 0.1)
				(type default)
			)
			(layer "B.Fab")
		)
		(fp_line
			(start -0.120396 0.2794)
			(end 0.12065 0.2794)
			(stroke
				(width 0.1)
				(type default)
			)
			(layer "B.Fab")
		)
		(fp_line
			(start 0.12065 0.2794)
			(end 0.12065 0.3048)
			(stroke
				(width 0.1)
				(type default)
			)
			(layer "B.Fab")
		)
		(fp_line
			(start -0.12065 -0.2794)
			(end -0.12065 -0.3048)
			(stroke
				(width 0.1)
				(type default)
			)
			(layer "B.Fab")
		)
		(fp_line
			(start 0.12065 -0.2794)
			(end -0.12065 -0.2794)
			(stroke
				(width 0.1)
				(type default)
			)
			(layer "B.Fab")
		)
		(fp_line
			(start -0.67945 -0.3048)
			(end -0.67945 0.3048)
			(stroke
				(width 0.1)
				(type default)
			)
			(layer "B.Fab")
		)
		(fp_line
			(start -0.12065 -0.3048)
			(end -0.67945 -0.3048)
			(stroke
				(width 0.1)
				(type default)
			)
			(layer "B.Fab")
		)
		(fp_line
			(start 0.12065 -0.305054)
			(end 0.12065 -0.2794)
			(stroke
				(width 0.1)
				(type default)
			)
			(layer "B.Fab")
		)
		(fp_line
			(start 0.67945 -0.305054)
			(end 0.12065 -0.305054)
			(stroke
				(width 0.1)
				(type default)
			)
			(layer "B.Fab")
		)
		(pad "1" smd circle
			(at 0.40005 0 90)
			(size 0 0)
			(layers "B.Cu" "B.Mask" "B.Paste")
			(net "PVCCINFAON_CPU0")
		)
		(pad "2" smd circle
			(at -0.40005 0 90)
			(size 0 0)
			(layers "B.Cu" "B.Mask" "B.Paste")
			(net "GND")
		)
	)
)
